(kicad_pcb
	(version 20260206)
	(generator "pcbnew")
	(generator_version "10.0")
	(general
		(thickness 1.6)
		(legacy_teardrops no)
	)
	(paper "A4")
	(title_block
		(title "03242023_DA0F0TMBIJ0_F0T_Motherboard_J_brd_V01_OCP.brd")
		(comment 1 "Grand Teton / footprints 3907-3913 of 6105")
	)
	(layers
		(0 "F.Cu" signal "TOP")
		(4 "In1.Cu" signal "GND")
		(6 "In2.Cu" signal "IN1")
		(8 "In3.Cu" signal "GND1")
		(10 "In4.Cu" signal "IN2")
		(12 "In5.Cu" signal "GND2")
		(14 "In6.Cu" signal "IN3")
		(16 "In7.Cu" signal "GND3")
		(18 "In8.Cu" signal "VCC")
		(20 "In9.Cu" signal "VCC1")
		(22 "In10.Cu" signal "GND4")
		(24 "In11.Cu" signal "IN4")
		(26 "In12.Cu" signal "GND5")
		(28 "In13.Cu" signal "IN5")
		(30 "In14.Cu" signal "GND6")
		(32 "In15.Cu" signal "IN6")
		(34 "In16.Cu" signal "GND7")
		(2 "B.Cu" signal "BOTTOM")
		(9 "F.Adhes" user "F.Adhesive")
		(11 "B.Adhes" user "B.Adhesive")
		(13 "F.Paste" user "Package Geometry/Pastemask Top")
		(15 "B.Paste" user "Package Geometry/Pastemask Bottom")
		(5 "F.SilkS" user "Ref Des/Silkscreen Top")
		(7 "B.SilkS" user "Ref Des/Silkscreen Bottom")
		(1 "F.Mask" user "Board Geometry/Soldermask Top")
		(3 "B.Mask" user "Board Geometry/Soldermask Bottom")
		(17 "Dwgs.User" user "User.Drawings")
		(19 "Cmts.User" user "User.Comments")
		(21 "Eco1.User" user "User.Eco1")
		(23 "Eco2.User" user "User.Eco2")
		(25 "Edge.Cuts" user "Board Geometry/Outline")
		(27 "Margin" user)
		(31 "F.CrtYd" user "Package Geometry/Place Bound Top")
		(29 "B.CrtYd" user "Package Geometry/Place Bound Bottom")
		(35 "F.Fab" user "Ref Des/Assembly Top")
		(33 "B.Fab" user "Ref Des/Assembly Bottom")
	)
	(footprint ""
		(layer "F.Cu")
		(at 151.69388 -22.824948 90)
		(property "Reference" "R2994"
			(at 0 0 90)
			(layer "F.SilkS")
			(hide yes)
			(effects
				(font
					(size 1.27 1.27)
				)
			)
		)
		(property "Value" ""
			(at 0 0 90)
			(layer "F.Fab")
			(effects
				(font
					(size 1.27 1.27)
				)
			)
		)
		(duplicate_pad_numbers_are_jumpers no)
		(fp_line
			(start 0.7874 -0.4064)
			(end 0.7874 0.4064)
			(stroke
				(width 0.1524)
				(type default)
			)
			(layer "F.SilkS")
		)
		(fp_line
			(start -0.7874 -0.4064)
			(end 0.7874 -0.4064)
			(stroke
				(width 0.1524)
				(type default)
			)
			(layer "F.SilkS")
		)
		(fp_line
			(start 0.7874 0.4064)
			(end -0.7874 0.4064)
			(stroke
				(width 0.1524)
				(type default)
			)
			(layer "F.SilkS")
		)
		(fp_line
			(start -0.7874 0.4064)
			(end -0.7874 -0.4064)
			(stroke
				(width 0.1524)
				(type default)
			)
			(layer "F.SilkS")
		)
		(fp_line
			(start -0.12065 -0.305054)
			(end -0.12065 -0.2794)
			(stroke
				(width 0.1)
				(type default)
			)
			(layer "F.Fab")
		)
		(fp_line
			(start -0.67945 -0.305054)
			(end -0.12065 -0.305054)
			(stroke
				(width 0.1)
				(type default)
			)
			(layer "F.Fab")
		)
		(fp_line
			(start 0.67945 -0.3048)
			(end 0.67945 0.3048)
			(stroke
				(width 0.1)
				(type default)
			)
			(layer "F.Fab")
		)
		(fp_line
			(start 0.12065 -0.3048)
			(end 0.67945 -0.3048)
			(stroke
				(width 0.1)
				(type default)
			)
			(layer "F.Fab")
		)
		(fp_line
			(start 0.12065 -0.2794)
			(end 0.12065 -0.3048)
			(stroke
				(width 0.1)
				(type default)
			)
			(layer "F.Fab")
		)
		(fp_line
			(start -0.12065 -0.2794)
			(end 0.12065 -0.2794)
			(stroke
				(width 0.1)
				(type default)
			)
			(layer "F.Fab")
		)
		(fp_line
			(start 0.120396 0.2794)
			(end -0.12065 0.2794)
			(stroke
				(width 0.1)
				(type default)
			)
			(layer "F.Fab")
		)
		(fp_line
			(start -0.12065 0.2794)
			(end -0.12065 0.3048)
			(stroke
				(width 0.1)
				(type default)
			)
			(layer "F.Fab")
		)
		(fp_line
			(start 0.67945 0.3048)
			(end 0.120396 0.3048)
			(stroke
				(width 0.1)
				(type default)
			)
			(layer "F.Fab")
		)
		(fp_line
			(start 0.120396 0.3048)
			(end 0.120396 0.2794)
			(stroke
				(width 0.1)
				(type default)
			)
			(layer "F.Fab")
		)
		(fp_line
			(start -0.12065 0.3048)
			(end -0.67945 0.3048)
			(stroke
				(width 0.1)
				(type default)
			)
			(layer "F.Fab")
		)
		(fp_line
			(start -0.67945 0.3048)
			(end -0.67945 -0.305054)
			(stroke
				(width 0.1)
				(type default)
			)
			(layer "F.Fab")
		)
		(pad "1" smd circle
			(at -0.40005 0 90)
			(size 0 0)
			(layers "F.Cu" "F.Mask" "F.Paste")
			(net "P3V_BAT_R1")
		)
		(pad "2" smd circle
			(at 0.40005 0 90)
			(size 0 0)
			(layers "F.Cu" "F.Mask" "F.Paste")
			(net "P3V_BAT_R")
		)
	)
	(footprint ""
		(layer "F.Cu")
		(at 27.628596 -388.262876 180)
		(property "Reference" "R3292"
			(at 0 0 180)
			(layer "F.SilkS")
			(hide yes)
			(effects
				(font
					(size 1.27 1.27)
				)
			)
		)
		(property "Value" ""
			(at 0 0 180)
			(layer "F.Fab")
			(effects
				(font
					(size 1.27 1.27)
				)
			)
		)
		(duplicate_pad_numbers_are_jumpers no)
		(fp_line
			(start 0.7874 0.4064)
			(end -0.7874 0.4064)
			(stroke
				(width 0.1524)
				(type default)
			)
			(layer "F.SilkS")
		)
		(fp_line
			(start 0.7874 -0.4064)
			(end 0.7874 0.4064)
			(stroke
				(width 0.1524)
				(type default)
			)
			(layer "F.SilkS")
		)
		(fp_line
			(start -0.7874 0.4064)
			(end -0.7874 -0.4064)
			(stroke
				(width 0.1524)
				(type default)
			)
			(layer "F.SilkS")
		)
		(fp_line
			(start -0.7874 -0.4064)
			(end 0.7874 -0.4064)
			(stroke
				(width 0.1524)
				(type default)
			)
			(layer "F.SilkS")
		)
		(fp_line
			(start 0.67945 0.3048)
			(end 0.120396 0.3048)
			(stroke
				(width 0.1)
				(type default)
			)
			(layer "F.Fab")
		)
		(fp_line
			(start 0.67945 -0.3048)
			(end 0.67945 0.3048)
			(stroke
				(width 0.1)
				(type default)
			)
			(layer "F.Fab")
		)
		(fp_line
			(start 0.12065 -0.2794)
			(end 0.12065 -0.3048)
			(stroke
				(width 0.1)
				(type default)
			)
			(layer "F.Fab")
		)
		(fp_line
			(start 0.12065 -0.3048)
			(end 0.67945 -0.3048)
			(stroke
				(width 0.1)
				(type default)
			)
			(layer "F.Fab")
		)
		(fp_line
			(start 0.120396 0.3048)
			(end 0.120396 0.2794)
			(stroke
				(width 0.1)
				(type default)
			)
			(layer "F.Fab")
		)
		(fp_line
			(start 0.120396 0.2794)
			(end -0.12065 0.2794)
			(stroke
				(width 0.1)
				(type default)
			)
			(layer "F.Fab")
		)
		(fp_line
			(start -0.12065 0.3048)
			(end -0.67945 0.3048)
			(stroke
				(width 0.1)
				(type default)
			)
			(layer "F.Fab")
		)
		(fp_line
			(start -0.12065 0.2794)
			(end -0.12065 0.3048)
			(stroke
				(width 0.1)
				(type default)
			)
			(layer "F.Fab")
		)
		(fp_line
			(start -0.12065 -0.2794)
			(end 0.12065 -0.2794)
			(stroke
				(width 0.1)
				(type default)
			)
			(layer "F.Fab")
		)
		(fp_line
			(start -0.12065 -0.305054)
			(end -0.12065 -0.2794)
			(stroke
				(width 0.1)
				(type default)
			)
			(layer "F.Fab")
		)
		(fp_line
			(start -0.67945 0.3048)
			(end -0.67945 -0.305054)
			(stroke
				(width 0.1)
				(type default)
			)
			(layer "F.Fab")
		)
		(fp_line
			(start -0.67945 -0.305054)
			(end -0.12065 -0.305054)
			(stroke
				(width 0.1)
				(type default)
			)
			(layer "F.Fab")
		)
		(pad "1" smd circle
			(at -0.40005 0 180)
			(size 0 0)
			(layers "F.Cu" "F.Mask" "F.Paste")
			(net "P3V3_AUX")
		)
		(pad "2" smd circle
			(at 0.40005 0 180)
			(size 0 0)
			(layers "F.Cu" "F.Mask" "F.Paste")
			(net "CLK_GEN2_GPU_FPGA_OE_OR_N")
		)
	)
	(footprint ""
		(layer "F.Cu")
		(at 107.296204 -245.634256 -90)
		(property "Reference" "C272"
			(at 0 0 270)
			(layer "F.SilkS")
			(hide yes)
			(effects
				(font
					(size 1.27 1.27)
				)
			)
		)
		(property "Value" ""
			(at 0 0 270)
			(layer "F.Fab")
			(effects
				(font
					(size 1.27 1.27)
				)
			)
		)
		(duplicate_pad_numbers_are_jumpers no)
		(fp_line
			(start -0.7874 0.4064)
			(end -0.7874 -0.4064)
			(stroke
				(width 0.1524)
				(type default)
			)
			(layer "F.SilkS")
		)
		(fp_line
			(start 0.7874 0.4064)
			(end -0.7874 0.4064)
			(stroke
				(width 0.1524)
				(type default)
			)
			(layer "F.SilkS")
		)
		(fp_line
			(start -0.7874 -0.4064)
			(end 0.7874 -0.4064)
			(stroke
				(width 0.1524)
				(type default)
			)
			(layer "F.SilkS")
		)
		(fp_line
			(start 0.7874 -0.4064)
			(end 0.7874 0.4064)
			(stroke
				(width 0.1524)
				(type default)
			)
			(layer "F.SilkS")
		)
		(fp_line
			(start -0.67945 0.3048)
			(end -0.67945 -0.305054)
			(stroke
				(width 0.1)
				(type default)
			)
			(layer "F.Fab")
		)
		(fp_line
			(start -0.12065 0.3048)
			(end -0.67945 0.3048)
			(stroke
				(width 0.1)
				(type default)
			)
			(layer "F.Fab")
		)
		(fp_line
			(start 0.120396 0.3048)
			(end 0.120396 0.2794)
			(stroke
				(width 0.1)
				(type default)
			)
			(layer "F.Fab")
		)
		(fp_line
			(start 0.67945 0.3048)
			(end 0.120396 0.3048)
			(stroke
				(width 0.1)
				(type default)
			)
			(layer "F.Fab")
		)
		(fp_line
			(start -0.12065 0.2794)
			(end -0.12065 0.3048)
			(stroke
				(width 0.1)
				(type default)
			)
			(layer "F.Fab")
		)
		(fp_line
			(start 0.120396 0.2794)
			(end -0.12065 0.2794)
			(stroke
				(width 0.1)
				(type default)
			)
			(layer "F.Fab")
		)
		(fp_line
			(start -0.12065 -0.2794)
			(end 0.12065 -0.2794)
			(stroke
				(width 0.1)
				(type default)
			)
			(layer "F.Fab")
		)
		(fp_line
			(start 0.12065 -0.2794)
			(end 0.12065 -0.3048)
			(stroke
				(width 0.1)
				(type default)
			)
			(layer "F.Fab")
		)
		(fp_line
			(start 0.12065 -0.3048)
			(end 0.67945 -0.3048)
			(stroke
				(width 0.1)
				(type default)
			)
			(layer "F.Fab")
		)
		(fp_line
			(start 0.67945 -0.3048)
			(end 0.67945 0.3048)
			(stroke
				(width 0.1)
				(type default)
			)
			(layer "F.Fab")
		)
		(fp_line
			(start -0.67945 -0.305054)
			(end -0.12065 -0.305054)
			(stroke
				(width 0.1)
				(type default)
			)
			(layer "F.Fab")
		)
		(fp_line
			(start -0.12065 -0.305054)
			(end -0.12065 -0.2794)
			(stroke
				(width 0.1)
				(type default)
			)
			(layer "F.Fab")
		)
		(pad "1" smd circle
			(at -0.40005 0 270)
			(size 0 0)
			(layers "F.Cu" "F.Mask" "F.Paste")
			(net "PVCCIN_CPU1")
		)
		(pad "2" smd circle
			(at 0.40005 0 270)
			(size 0 0)
			(layers "F.Cu" "F.Mask" "F.Paste")
			(net "GND")
		)
	)
	(footprint ""
		(layer "F.Cu")
		(at 307.363622 -41.900348 180)
		(property "Reference" "R1300"
			(at 0 0 180)
			(layer "F.SilkS")
			(hide yes)
			(effects
				(font
					(size 1.27 1.27)
				)
			)
		)
		(property "Value" ""
			(at 0 0 180)
			(layer "F.Fab")
			(effects
				(font
					(size 1.27 1.27)
				)
			)
		)
		(duplicate_pad_numbers_are_jumpers no)
		(fp_line
			(start 0.7874 0.4064)
			(end -0.7874 0.4064)
			(stroke
				(width 0.1524)
				(type default)
			)
			(layer "F.SilkS")
		)
		(fp_line
			(start 0.7874 -0.4064)
			(end 0.7874 0.4064)
			(stroke
				(width 0.1524)
				(type default)
			)
			(layer "F.SilkS")
		)
		(fp_line
			(start -0.7874 0.4064)
			(end -0.7874 -0.4064)
			(stroke
				(width 0.1524)
				(type default)
			)
			(layer "F.SilkS")
		)
		(fp_line
			(start -0.7874 -0.4064)
			(end 0.7874 -0.4064)
			(stroke
				(width 0.1524)
				(type default)
			)
			(layer "F.SilkS")
		)
		(fp_line
			(start 0.67945 0.3048)
			(end 0.120396 0.3048)
			(stroke
				(width 0.1)
				(type default)
			)
			(layer "F.Fab")
		)
		(fp_line
			(start 0.67945 -0.3048)
			(end 0.67945 0.3048)
			(stroke
				(width 0.1)
				(type default)
			)
			(layer "F.Fab")
		)
		(fp_line
			(start 0.12065 -0.2794)
			(end 0.12065 -0.3048)
			(stroke
				(width 0.1)
				(type default)
			)
			(layer "F.Fab")
		)
		(fp_line
			(start 0.12065 -0.3048)
			(end 0.67945 -0.3048)
			(stroke
				(width 0.1)
				(type default)
			)
			(layer "F.Fab")
		)
		(fp_line
			(start 0.120396 0.3048)
			(end 0.120396 0.2794)
			(stroke
				(width 0.1)
				(type default)
			)
			(layer "F.Fab")
		)
		(fp_line
			(start 0.120396 0.2794)
			(end -0.12065 0.2794)
			(stroke
				(width 0.1)
				(type default)
			)
			(layer "F.Fab")
		)
		(fp_line
			(start -0.12065 0.3048)
			(end -0.67945 0.3048)
			(stroke
				(width 0.1)
				(type default)
			)
			(layer "F.Fab")
		)
		(fp_line
			(start -0.12065 0.2794)
			(end -0.12065 0.3048)
			(stroke
				(width 0.1)
				(type default)
			)
			(layer "F.Fab")
		)
		(fp_line
			(start -0.12065 -0.2794)
			(end 0.12065 -0.2794)
			(stroke
				(width 0.1)
				(type default)
			)
			(layer "F.Fab")
		)
		(fp_line
			(start -0.12065 -0.305054)
			(end -0.12065 -0.2794)
			(stroke
				(width 0.1)
				(type default)
			)
			(layer "F.Fab")
		)
		(fp_line
			(start -0.67945 0.3048)
			(end -0.67945 -0.305054)
			(stroke
				(width 0.1)
				(type default)
			)
			(layer "F.Fab")
		)
		(fp_line
			(start -0.67945 -0.305054)
			(end -0.12065 -0.305054)
			(stroke
				(width 0.1)
				(type default)
			)
			(layer "F.Fab")
		)
		(pad "1" smd circle
			(at -0.40005 0 180)
			(size 0 0)
			(layers "F.Cu" "F.Mask" "F.Paste")
			(net "FM_BIOS_POST_CMPLT_N")
		)
		(pad "2" smd circle
			(at 0.40005 0 180)
			(size 0 0)
			(layers "F.Cu" "F.Mask" "F.Paste")
			(net "FM_BIOS_POST_CMPLT_BMC_N")
		)
	)
	(footprint ""
		(layer "F.Cu")
		(at 325.605902 -20.548346 -90)
		(property "Reference" "R1487"
			(at 0 0 270)
			(layer "F.SilkS")
			(hide yes)
			(effects
				(font
					(size 1.27 1.27)
				)
			)
		)
		(property "Value" ""
			(at 0 0 270)
			(layer "F.Fab")
			(effects
				(font
					(size 1.27 1.27)
				)
			)
		)
		(duplicate_pad_numbers_are_jumpers no)
		(fp_line
			(start -0.7874 0.4064)
			(end -0.7874 -0.4064)
			(stroke
				(width 0.1524)
				(type default)
			)
			(layer "F.SilkS")
		)
		(fp_line
			(start 0.7874 0.4064)
			(end -0.7874 0.4064)
			(stroke
				(width 0.1524)
				(type default)
			)
			(layer "F.SilkS")
		)
		(fp_line
			(start -0.7874 -0.4064)
			(end 0.7874 -0.4064)
			(stroke
				(width 0.1524)
				(type default)
			)
			(layer "F.SilkS")
		)
		(fp_line
			(start 0.7874 -0.4064)
			(end 0.7874 0.4064)
			(stroke
				(width 0.1524)
				(type default)
			)
			(layer "F.SilkS")
		)
		(fp_line
			(start -0.67945 0.3048)
			(end -0.67945 -0.305054)
			(stroke
				(width 0.1)
				(type default)
			)
			(layer "F.Fab")
		)
		(fp_line
			(start -0.12065 0.3048)
			(end -0.67945 0.3048)
			(stroke
				(width 0.1)
				(type default)
			)
			(layer "F.Fab")
		)
		(fp_line
			(start 0.120396 0.3048)
			(end 0.120396 0.2794)
			(stroke
				(width 0.1)
				(type default)
			)
			(layer "F.Fab")
		)
		(fp_line
			(start 0.67945 0.3048)
			(end 0.120396 0.3048)
			(stroke
				(width 0.1)
				(type default)
			)
			(layer "F.Fab")
		)
		(fp_line
			(start -0.12065 0.2794)
			(end -0.12065 0.3048)
			(stroke
				(width 0.1)
				(type default)
			)
			(layer "F.Fab")
		)
		(fp_line
			(start 0.120396 0.2794)
			(end -0.12065 0.2794)
			(stroke
				(width 0.1)
				(type default)
			)
			(layer "F.Fab")
		)
		(fp_line
			(start -0.12065 -0.2794)
			(end 0.12065 -0.2794)
			(stroke
				(width 0.1)
				(type default)
			)
			(layer "F.Fab")
		)
		(fp_line
			(start 0.12065 -0.2794)
			(end 0.12065 -0.3048)
			(stroke
				(width 0.1)
				(type default)
			)
			(layer "F.Fab")
		)
		(fp_line
			(start 0.12065 -0.3048)
			(end 0.67945 -0.3048)
			(stroke
				(width 0.1)
				(type default)
			)
			(layer "F.Fab")
		)
		(fp_line
			(start 0.67945 -0.3048)
			(end 0.67945 0.3048)
			(stroke
				(width 0.1)
				(type default)
			)
			(layer "F.Fab")
		)
		(fp_line
			(start -0.67945 -0.305054)
			(end -0.12065 -0.305054)
			(stroke
				(width 0.1)
				(type default)
			)
			(layer "F.Fab")
		)
		(fp_line
			(start -0.12065 -0.305054)
			(end -0.12065 -0.2794)
			(stroke
				(width 0.1)
				(type default)
			)
			(layer "F.Fab")
		)
		(pad "1" smd circle
			(at -0.40005 0 270)
			(size 0 0)
			(layers "F.Cu" "F.Mask" "F.Paste")
			(net "FM_PCH_SATA_RAID_KEY")
		)
		(pad "2" smd circle
			(at 0.40005 0 270)
			(size 0 0)
			(layers "F.Cu" "F.Mask" "F.Paste")
			(net "GND")
		)
	)
	(footprint ""
		(layer "F.Cu")
		(at 312.341768 -408.517344 -90)
		(property "Reference" "C907"
			(at 0 0 270)
			(layer "F.SilkS")
			(hide yes)
			(effects
				(font
					(size 1.27 1.27)
				)
			)
		)
		(property "Value" ""
			(at 0 0 270)
			(layer "F.Fab")
			(effects
				(font
					(size 1.27 1.27)
				)
			)
		)
		(duplicate_pad_numbers_are_jumpers no)
		(fp_line
			(start -0.299974 0.150114)
			(end -0.299974 -0.150114)
			(stroke
				(width 0.1)
				(type default)
			)
			(layer "F.Fab")
		)
		(fp_line
			(start 0.299974 0.150114)
			(end -0.299974 0.150114)
			(stroke
				(width 0.1)
				(type default)
			)
			(layer "F.Fab")
		)
		(fp_line
			(start -0.299974 -0.150114)
			(end 0.299974 -0.150114)
			(stroke
				(width 0.1)
				(type default)
			)
			(layer "F.Fab")
		)
		(fp_line
			(start 0.299974 -0.150114)
			(end 0.299974 0.150114)
			(stroke
				(width 0.1)
				(type default)
			)
			(layer "F.Fab")
		)
		(pad "1" smd rect
			(at -0.2667 0 270)
			(size 0.3048 0.381)
			(layers "F.Cu" "F.Mask" "F.Paste")
			(net "P5E_CPU0_PE0_TX_C_DP<13>")
		)
		(pad "2" smd rect
			(at 0.2667 0 270)
			(size 0.3048 0.381)
			(layers "F.Cu" "F.Mask" "F.Paste")
			(net "P5E_CPU0_PE0_TX_DP<13>")
		)
	)
	(footprint ""
		(layer "F.Cu")
		(at 401.22729 -408.517344 -90)
		(property "Reference" "C889"
			(at 0 0 270)
			(layer "F.SilkS")
			(hide yes)
			(effects
				(font
					(size 1.27 1.27)
				)
			)
		)
		(property "Value" ""
			(at 0 0 270)
			(layer "F.Fab")
			(effects
				(font
					(size 1.27 1.27)
				)
			)
		)
		(duplicate_pad_numbers_are_jumpers no)
		(fp_line
			(start -0.299974 0.150114)
			(end -0.299974 -0.150114)
			(stroke
				(width 0.1)
				(type default)
			)
			(layer "F.Fab")
		)
		(fp_line
			(start 0.299974 0.150114)
			(end -0.299974 0.150114)
			(stroke
				(width 0.1)
				(type default)
			)
			(layer "F.Fab")
		)
		(fp_line
			(start -0.299974 -0.150114)
			(end 0.299974 -0.150114)
			(stroke
				(width 0.1)
				(type default)
			)
			(layer "F.Fab")
		)
		(fp_line
			(start 0.299974 -0.150114)
			(end 0.299974 0.150114)
			(stroke
				(width 0.1)
				(type default)
			)
			(layer "F.Fab")
		)
		(pad "1" smd rect
			(at -0.2667 0 270)
			(size 0.3048 0.381)
			(layers "F.Cu" "F.Mask" "F.Paste")
			(net "P5E_CPU0_PE3_TX_C_DP<6>")
		)
		(pad "2" smd rect
			(at 0.2667 0 270)
			(size 0.3048 0.381)
			(layers "F.Cu" "F.Mask" "F.Paste")
			(net "P5E_CPU0_PE3_TX_DP<6>")
		)
	)
)
